FILE_TYPE=LIBRARY_PARTS;
primitive 'MPQ8633BGLEC838Z';
  pin
    'VIN1':
      PIN_NUMBER='(10)';
      INPUT_LOAD='(-0.01,0.01)';
    'PGOOD':
      PIN_NUMBER='(9)';
      OUTPUT_LOAD='(1.0,-1.0)';
    'PGND':
      PIN_NUMBER='(11_18)';
      PINUSE='POWER';
      NO_LOAD_CHECK='Both';
      NO_IO_CHECK='Both';
      NO_ASSERT_CHECK='TRUE';
      NO_DIR_CHECK='TRUE';
      ALLOW_CONNECT='TRUE';
    'EN':
      PIN_NUMBER='(8)';
      INPUT_LOAD='(-0.01,0.01)';
    'BST':
      PIN_NUMBER='(1)';
      INPUT_LOAD='(-0.01,0.01)';
    'FB':
      PIN_NUMBER='(7)';
      INPUT_LOAD='(-0.01,0.01)';
    'AGND':
      PIN_NUMBER='(2)';
      PINUSE='POWER';
      NO_LOAD_CHECK='Both';
      NO_IO_CHECK='Both';
      NO_ASSERT_CHECK='TRUE';
      NO_DIR_CHECK='TRUE';
      ALLOW_CONNECT='TRUE';
    'VCC':
      PIN_NUMBER='(19)';
      INPUT_LOAD='(-0.01,0.01)';
    'RGND':
      PIN_NUMBER='(6)';
      PINUSE='POWER';
      NO_LOAD_CHECK='Both';
      NO_IO_CHECK='Both';
      NO_ASSERT_CHECK='TRUE';
      NO_DIR_CHECK='TRUE';
      ALLOW_CONNECT='TRUE';
    'SW':
      PIN_NUMBER='(20)';
      OUTPUT_LOAD='(1.0,-1.0)';
    'TRK_REF':
      PIN_NUMBER='(5)';
      INPUT_LOAD='(-0.01,0.01)';
    'MODE':
      PIN_NUMBER='(4)';
      INPUT_LOAD='(-0.01,0.01)';
    'CS':
      PIN_NUMBER='(3)';
      INPUT_LOAD='(-0.01,0.01)';
    'VIN2':
      PIN_NUMBER='(21)';
      INPUT_LOAD='(-0.01,0.01)';
  end_pin;
  body
    PART_NAME='MPQ8633BGLEC838Z';
    BODY_NAME='MPQ8633BGLEC838Z';
    PHYS_DES_PREFIX='U';
    CLASS='IC';
  end_body;
end_primitive;

END.
